# BASEBOARD_FAB2 (Tioga Pass) — schematic netlist excerpt (pin names and nets, part order shuffled) for the footprints in the layout excerpt that follows; sources: Cadence DE-HDL packaged netlist, KiCad conversion of Wiwynn_Tioga_Pass_MB.brd

EU4D5  PXE1110B  IC  pkg QFN  page 213
  DNC(0)  = NC
  DNC(1)  = NC
  BPWM1  = NC
  DNC(2)  = NC
  APWM1  = VR_PVCCIO_CPU1_PWM1
  SDA  = SMB_VR_STBY_LVC3_SDA
  SCL  = SMB_VR_STBY_LVC3_SCL
  RESET_N  = NC
  AVRRDY  = PWRGD_PVCCIO_CPU1_R
  AVREN  = VR_PVCCIO_CPU1_EN
  VRHOT_N  = IRQ_PVCCIO_CPU1_VRHOT_N
  PINALRT_N  = NC
  MP0  = NC
  MP1  = NC
  VCLK  = SVID_CLK_PVCCIO_CPU1
  VDIO  = SVID_VDIO_PVCCIO_CPU1
  VALRT_N  = SVID_ALERT_PVCCIO_CPU1
  MP2  = NC
  AVSEN  = VR_PVCCIO_CPU1_AVSP
  AVREF  = VSENSE_PVCCIO_CPU1_AVSN
  AIREF1  = VR_PVCCIO_CPU1_AIREF1
  AISEN1  = ISENSE_PVCCIO_CPU1_PH1_IMON
  GND(1)  = GND
  DNC(3)  = NC
  BIREF1  = NC
  BISEN1  = GND
  GND(0)  = GND
  DNC(4)  = NC
  BVSEN  = NC
  BVREF  = NC
  MP3  = NC
  MP4  = PU_VR_PVCCIO_CPU1_FAULT1
  XADDR2  = VR_PVCCIO_CPU1_XADDR2
  BTSEN  = NC
  ATSEN  = A_TSENSE_PVCCIO_CPU1
  XADDR1  = VR_PVCCIO_CPU1_XADDR1
  VINSEN  = VR_PVCCIO_CPU1_VINSEN
  IINSEN  = NC
  VDD  = VR_PVCCIO_CPU1_VDD
  VD12  = VR_PVCCIO_CPU1_VD12
  THPAD  = GND

(kicad_pcb
	(version 20260206)
	(generator "pcbnew")
	(generator_version "10.0")
	(general
		(thickness 1.6)
		(legacy_teardrops no)
	)
	(paper "A4")
	(title_block
		(title "Wiwynn_Tioga_Pass_MB.brd")
		(comment 1 "Tioga Pass / footprint 313 of 4770 (EU4D5), pads 35-41 of 41")
	)
	(layers
		(0 "F.Cu" signal "TOP")
		(4 "In1.Cu" signal "L2GND")
		(6 "In2.Cu" signal "L3")
		(8 "In3.Cu" signal "L4GND")
		(10 "In4.Cu" signal "L5")
		(12 "In5.Cu" signal "L6GND")
		(14 "In6.Cu" signal "L7VCC")
		(16 "In7.Cu" signal "L8VCC")
		(18 "In8.Cu" signal "L9GND")
		(20 "In9.Cu" signal "L10")
		(22 "In10.Cu" signal "L11GND")
		(24 "In11.Cu" signal "L12")
		(26 "In12.Cu" signal "L13GND")
		(2 "B.Cu" signal "BOTTOM")
		(9 "F.Adhes" user "F.Adhesive")
		(11 "B.Adhes" user "B.Adhesive")
		(13 "F.Paste" user "Package Geometry/Pastemask Top")
		(15 "B.Paste" user "Package Geometry/Pastemask Bottom")
		(5 "F.SilkS" user "Ref Des/Silkscreen Top")
		(7 "B.SilkS" user "Ref Des/Silkscreen Bottom")
		(1 "F.Mask" user "Board Geometry/Soldermask Top")
		(3 "B.Mask" user "Board Geometry/Soldermask Bottom")
		(17 "Dwgs.User" user "User.Drawings")
		(19 "Cmts.User" user "User.Comments")
		(21 "Eco1.User" user "User.Eco1")
		(23 "Eco2.User" user "User.Eco2")
		(25 "Edge.Cuts" user "Board Geometry/Outline")
		(27 "Margin" user)
		(31 "F.CrtYd" user "Package Geometry/Place Bound Top")
		(29 "B.CrtYd" user "Package Geometry/Place Bound Bottom")
		(35 "F.Fab" user "Ref Des/Assembly Top")
		(33 "B.Fab" user "Ref Des/Assembly Bottom")
	)
	(footprint ""
		(layer "F.Cu")
		(at 169.1894 -66.802 -90)
		(property "Reference" "EU4D5"
			(at 0.6096 -3.60807 90)
			(unlocked yes)
			(layer "F.SilkS")
			(effects
				(font
					(size 0.7874 0.5842)
					(thickness 0.1524)
				)
				(justify left)
			)
		)
		(property "Value" ""
			(at 0 0 270)
			(layer "F.Fab")
			(effects
				(font
					(size 1.27 1.27)
				)
			)
		)
		(duplicate_pad_numbers_are_jumpers no)
		(pad "35" smd custom
			(at 0.199898 -2.4511 270)
			(size 0.0508 0.0508)
			(layers "F.Cu" "F.Mask" "F.Paste")
			(net "A_TSENSE_PVCCIO_CPU1")
			(options
				(clearance outline)
				(anchor circle)
			)
			(primitives
				(gr_poly
					(pts
						(arc
							(start 0.1016 0.254)
							(mid 0 0.3556)
							(end -0.1016 0.254)
						)
						(xy -0.1016 -0.3556) (xy 0.1016 -0.3556)
					)
					(width 0)
					(fill yes)
				)
			)
		)
		(pad "36" smd custom
			(at -0.199898 -2.4511 270)
			(size 0.0508 0.0508)
			(layers "F.Cu" "F.Mask" "F.Paste")
			(net "VR_PVCCIO_CPU1_XADDR1")
			(options
				(clearance outline)
				(anchor circle)
			)
			(primitives
				(gr_poly
					(pts
						(arc
							(start 0.1016 0.254)
							(mid 0 0.3556)
							(end -0.1016 0.254)
						)
						(xy -0.1016 -0.3556) (xy 0.1016 -0.3556)
					)
					(width 0)
					(fill yes)
				)
			)
		)
		(pad "37" smd custom
			(at -0.599948 -2.4511 270)
			(size 0.0508 0.0508)
			(layers "F.Cu" "F.Mask" "F.Paste")
			(net "VR_PVCCIO_CPU1_VINSEN")
			(options
				(clearance outline)
				(anchor circle)
			)
			(primitives
				(gr_poly
					(pts
						(arc
							(start 0.1016 0.254)
							(mid 0 0.3556)
							(end -0.1016 0.254)
						)
						(xy -0.1016 -0.3556) (xy 0.1016 -0.3556)
					)
					(width 0)
					(fill yes)
				)
			)
		)
		(pad "38" smd custom
			(at -0.999998 -2.4511 270)
			(size 0.0508 0.0508)
			(layers "F.Cu" "F.Mask" "F.Paste")
			(net "Net_266")
			(options
				(clearance outline)
				(anchor circle)
			)
			(primitives
				(gr_poly
					(pts
						(arc
							(start 0.1016 0.254)
							(mid 0 0.3556)
							(end -0.1016 0.254)
						)
						(xy -0.1016 -0.3556) (xy 0.1016 -0.3556)
					)
					(width 0)
					(fill yes)
				)
			)
		)
		(pad "39" smd custom
			(at -1.400048 -2.4511 270)
			(size 0.0508 0.0508)
			(layers "F.Cu" "F.Mask" "F.Paste")
			(net "VR_PVCCIO_CPU1_VDD")
			(options
				(clearance outline)
				(anchor circle)
			)
			(primitives
				(gr_poly
					(pts
						(arc
							(start 0.1016 0.254)
							(mid 0 0.3556)
							(end -0.1016 0.254)
						)
						(xy -0.1016 -0.3556) (xy 0.1016 -0.3556)
					)
					(width 0)
					(fill yes)
				)
			)
		)
		(pad "40" smd custom
			(at -1.800098 -2.4511 270)
			(size 0.0508 0.0508)
			(layers "F.Cu" "F.Mask" "F.Paste")
			(net "VR_PVCCIO_CPU1_VD12")
			(options
				(clearance outline)
				(anchor circle)
			)
			(primitives
				(gr_poly
					(pts
						(arc
							(start 0.1016 0.254)
							(mid 0 0.3556)
							(end -0.1016 0.254)
						)
						(xy -0.1016 -0.3556) (xy 0.1016 -0.3556)
					)
					(width 0)
					(fill yes)
				)
			)
		)
		(pad "41" smd rect
			(at 0 0 270)
			(size 3.683 3.683)
			(layers "F.Cu" "F.Mask" "F.Paste")
			(net "GND")
		)
	)
)
